# BASEBOARD_FAB2 (Tioga Pass) — schematic netlist excerpt (pin names and nets, part order shuffled) for the footprints in the layout excerpt that follows; sources: Cadence DE-HDL packaged netlist, KiCad conversion of Wiwynn_Tioga_Pass_MB.brd

L25W3  IND-68NH-15-GP  pkg DISCRET-GC1  page 252 : \1\ = BMC_VGA_RED ; \2\ = V_IO_R_J
R9N16  RES  0.0 5% CHIP  pkg 0402  page 206 : A = FM_PVCCIN_PVCCSA_CPU1_EN_LVC1 ; B = VR_PVCCIN_CPU1_VREN
C25W24  CAP  1.0UF 16V 10% X6S  pkg 0402  page 149 : A = P1V15_AUX_BMC ; B = GND

(kicad_pcb
	(version 20260206)
	(generator "pcbnew")
	(generator_version "10.0")
	(general
		(thickness 1.6)
		(legacy_teardrops no)
	)
	(paper "A4")
	(title_block
		(title "Wiwynn_Tioga_Pass_MB.brd")
		(comment 1 "Tioga Pass / footprints 3812-3814 of 4770")
	)
	(layers
		(0 "F.Cu" signal "TOP")
		(4 "In1.Cu" signal "L2GND")
		(6 "In2.Cu" signal "L3")
		(8 "In3.Cu" signal "L4GND")
		(10 "In4.Cu" signal "L5")
		(12 "In5.Cu" signal "L6GND")
		(14 "In6.Cu" signal "L7VCC")
		(16 "In7.Cu" signal "L8VCC")
		(18 "In8.Cu" signal "L9GND")
		(20 "In9.Cu" signal "L10")
		(22 "In10.Cu" signal "L11GND")
		(24 "In11.Cu" signal "L12")
		(26 "In12.Cu" signal "L13GND")
		(2 "B.Cu" signal "BOTTOM")
		(9 "F.Adhes" user "F.Adhesive")
		(11 "B.Adhes" user "B.Adhesive")
		(13 "F.Paste" user "Package Geometry/Pastemask Top")
		(15 "B.Paste" user "Package Geometry/Pastemask Bottom")
		(5 "F.SilkS" user "Ref Des/Silkscreen Top")
		(7 "B.SilkS" user "Ref Des/Silkscreen Bottom")
		(1 "F.Mask" user "Board Geometry/Soldermask Top")
		(3 "B.Mask" user "Board Geometry/Soldermask Bottom")
		(17 "Dwgs.User" user "User.Drawings")
		(19 "Cmts.User" user "User.Comments")
		(21 "Eco1.User" user "User.Eco1")
		(23 "Eco2.User" user "User.Eco2")
		(25 "Edge.Cuts" user "Board Geometry/Outline")
		(27 "Margin" user)
		(31 "F.CrtYd" user "Package Geometry/Place Bound Top")
		(29 "B.CrtYd" user "Package Geometry/Place Bound Bottom")
		(35 "F.Fab" user "Ref Des/Assembly Top")
		(33 "B.Fab" user "Ref Des/Assembly Bottom")
	)
	(footprint ""
		(layer "B.Cu")
		(at 418.846 -24.765 90)
		(property "Reference" "L25W3"
			(at 0 0 90)
			(layer "B.SilkS")
			(hide yes)
			(effects
				(font
					(size 1.27 1.27)
				)
				(justify mirror)
			)
		)
		(property "Value" "*"
			(at -0.0254 -2.8829 90)
			(unlocked yes)
			(layer "B.Fab")
			(hide yes)
			(effects
				(font
					(size 1.27 1.016)
					(thickness 0.1524)
				)
				(justify mirror)
			)
		)
		(property "Device Type" "IND-68NH-15-GP_DISCRET-GC1-INDA"
			(at -0.0254 -4.4069 90)
			(unlocked yes)
			(layer "B.Fab")
			(hide yes)
			(effects
				(font
					(size 1.27 1.016)
					(thickness 0.1524)
				)
				(justify mirror)
			)
		)
		(duplicate_pad_numbers_are_jumpers no)
		(fp_line
			(start -0.254 0)
			(end 0.254 0)
			(stroke
				(width 0.2032)
				(type default)
			)
			(layer "B.SilkS")
		)
		(fp_rect
			(start 0.5842 1.3335)
			(end -0.5842 -1.3335)
			(stroke
				(width 0)
				(type default)
			)
			(fill no)
			(layer "B.CrtYd")
		)
		(fp_rect
			(start 0.5842 1.3335)
			(end -0.5842 -1.3335)
			(stroke
				(width 0)
				(type default)
			)
			(fill no)
			(layer "B.Fab")
		)
		(pad "1" smd custom
			(at 0 -0.762 270)
			(size 0.2159 0.2159)
			(layers "B.Cu" "B.Mask" "B.Paste")
			(net "BMC_VGA_RED")
			(options
				(clearance outline)
				(anchor circle)
			)
			(primitives
				(gr_poly
					(pts
						(arc
							(start -0.3302 0.4318)
							(mid -0.402042 0.402042)
							(end -0.4318 0.3302)
						)
						(arc
							(start -0.4318 -0.3302)
							(mid -0.402042 -0.402042)
							(end -0.3302 -0.4318)
						)
						(arc
							(start 0.3302 -0.4318)
							(mid 0.402042 -0.402042)
							(end 0.4318 -0.3302)
						)
						(arc
							(start 0.4318 0.3302)
							(mid 0.402042 0.402042)
							(end 0.3302 0.4318)
						)
					)
					(width 0)
					(fill yes)
				)
			)
		)
		(pad "2" smd custom
			(at 0 0.762 270)
			(size 0.2159 0.2159)
			(layers "B.Cu" "B.Mask" "B.Paste")
			(net "V_IO_R_J")
			(options
				(clearance outline)
				(anchor circle)
			)
			(primitives
				(gr_poly
					(pts
						(arc
							(start -0.3302 0.4318)
							(mid -0.402042 0.402042)
							(end -0.4318 0.3302)
						)
						(arc
							(start -0.4318 -0.3302)
							(mid -0.402042 -0.402042)
							(end -0.3302 -0.4318)
						)
						(arc
							(start 0.3302 -0.4318)
							(mid 0.402042 -0.402042)
							(end 0.4318 -0.3302)
						)
						(arc
							(start 0.4318 0.3302)
							(mid 0.402042 0.402042)
							(end 0.3302 0.4318)
						)
					)
					(width 0)
					(fill yes)
				)
			)
		)
	)
	(footprint ""
		(layer "B.Cu")
		(at 13.843 -89.154 90)
		(property "Reference" "R9N16"
			(at 0 0 90)
			(layer "B.SilkS")
			(hide yes)
			(effects
				(font
					(size 1.27 1.27)
				)
				(justify mirror)
			)
		)
		(property "Value" ""
			(at 0 0 90)
			(layer "B.Fab")
			(effects
				(font
					(size 1.27 1.27)
				)
				(justify mirror)
			)
		)
		(duplicate_pad_numbers_are_jumpers no)
		(fp_rect
			(start -0.2794 -0.1016)
			(end 0.2794 0.9906)
			(stroke
				(width 0)
				(type default)
			)
			(fill no)
			(layer "B.CrtYd")
		)
		(fp_line
			(start 0.2794 -0.1016)
			(end 0.2794 0.9906)
			(stroke
				(width 0.1)
				(type default)
			)
			(layer "B.Fab")
		)
		(fp_line
			(start -0.2794 -0.1016)
			(end 0.2794 -0.1016)
			(stroke
				(width 0.1)
				(type default)
			)
			(layer "B.Fab")
		)
		(fp_line
			(start 0.2794 0.9906)
			(end -0.2794 0.9906)
			(stroke
				(width 0.1)
				(type default)
			)
			(layer "B.Fab")
		)
		(fp_line
			(start -0.2794 0.9906)
			(end -0.2794 -0.1016)
			(stroke
				(width 0.1)
				(type default)
			)
			(layer "B.Fab")
		)
		(pad "1" smd rect
			(at 0 0 270)
			(size 0.508 0.508)
			(layers "B.Cu" "B.Mask" "B.Paste")
			(net "FM_PVCCIN_PVCCSA_CPU1_EN_LVC1")
		)
		(pad "2" smd rect
			(at 0 0.889 270)
			(size 0.508 0.508)
			(layers "B.Cu" "B.Mask" "B.Paste")
			(net "VR_PVCCIN_CPU1_VREN")
		)
		(zone
			(layer "B.Cu")
			(hatch none 0.5)
			(connect_pads
				(clearance 0)
			)
			(min_thickness 0.25)
			(keepout
				(tracks not_allowed)
				(vias allowed)
				(pads allowed)
				(copperpour not_allowed)
				(footprints allowed)
			)
			(placement
				(enabled no)
				(sheetname "")
			)
			(fill
				(thermal_gap 0.5)
				(thermal_bridge_width 0.5)
				(island_removal_mode 0)
			)
			(polygon
				(pts
					(xy 14.097 -88.9) (xy 14.478 -88.9) (xy 14.478 -89.408) (xy 14.097 -89.408)
				)
			)
		)
		(zone
			(layer "B.Cu")
			(hatch none 0.5)
			(connect_pads
				(clearance 0)
			)
			(min_thickness 0.25)
			(keepout
				(tracks allowed)
				(vias not_allowed)
				(pads allowed)
				(copperpour not_allowed)
				(footprints allowed)
			)
			(placement
				(enabled no)
				(sheetname "")
			)
			(fill
				(thermal_gap 0.5)
				(thermal_bridge_width 0.5)
				(island_removal_mode 0)
			)
			(polygon
				(pts
					(xy 14.097 -88.9) (xy 14.478 -88.9) (xy 14.478 -89.408) (xy 14.097 -89.408)
				)
			)
		)
	)
	(footprint ""
		(layer "B.Cu")
		(at 417.919916 -35.202368 -90)
		(property "Reference" "C25W24"
			(at 0.8382 -0.67818 270)
			(unlocked yes)
			(layer "B.SilkS")
			(effects
				(font
					(size 0.4064 0.254)
					(thickness 0.1524)
				)
				(justify left mirror)
			)
		)
		(property "Value" ""
			(at 0 0 90)
			(layer "B.Fab")
			(effects
				(font
					(size 1.27 1.27)
				)
				(justify mirror)
			)
		)
		(duplicate_pad_numbers_are_jumpers no)
		(fp_poly
			(pts
				(xy -0.3048 -0.1016) (xy -0.3048 0.9906) (xy 0.3048 0.9906) (xy 0.3048 -0.1016)
			)
			(stroke
				(width 0)
				(type default)
			)
			(fill no)
			(layer "B.CrtYd")
		)
		(fp_line
			(start -0.3048 0.9906)
			(end -0.3048 -0.1016)
			(stroke
				(width 0.1)
				(type default)
			)
			(layer "B.Fab")
		)
		(fp_line
			(start 0.3048 0.9906)
			(end -0.3048 0.9906)
			(stroke
				(width 0.1)
				(type default)
			)
			(layer "B.Fab")
		)
		(fp_line
			(start -0.3048 -0.1016)
			(end 0.3048 -0.1016)
			(stroke
				(width 0.1)
				(type default)
			)
			(layer "B.Fab")
		)
		(fp_line
			(start 0.3048 -0.1016)
			(end 0.3048 0.9906)
			(stroke
				(width 0.1)
				(type default)
			)
			(layer "B.Fab")
		)
		(pad "1" smd rect
			(at 0 0 90)
			(size 0.508 0.508)
			(layers "B.Cu" "B.Mask" "B.Paste")
			(net "P1V15_AUX_BMC")
		)
		(pad "2" smd rect
			(at 0 0.889 90)
			(size 0.508 0.508)
			(layers "B.Cu" "B.Mask" "B.Paste")
			(net "GND")
		)
		(zone
			(layer "B.Cu")
			(hatch none 0.5)
			(connect_pads
				(clearance 0)
			)
			(min_thickness 0.25)
			(keepout
				(tracks not_allowed)
				(vias allowed)
				(pads allowed)
				(copperpour not_allowed)
				(footprints allowed)
			)
			(placement
				(enabled no)
				(sheetname "")
			)
			(fill
				(thermal_gap 0.5)
				(thermal_bridge_width 0.5)
				(island_removal_mode 0)
			)
			(polygon
				(pts
					(xy 417.284916 -34.948368) (xy 417.284916 -35.456368) (xy 417.665916 -35.456368) (xy 417.665916 -34.948368)
				)
			)
		)
		(zone
			(layer "B.Cu")
			(hatch none 0.5)
			(connect_pads
				(clearance 0)
			)
			(min_thickness 0.25)
			(keepout
				(tracks allowed)
				(vias not_allowed)
				(pads allowed)
				(copperpour not_allowed)
				(footprints allowed)
			)
			(placement
				(enabled no)
				(sheetname "")
			)
			(fill
				(thermal_gap 0.5)
				(thermal_bridge_width 0.5)
				(island_removal_mode 0)
			)
			(polygon
				(pts
					(xy 417.665916 -34.948368) (xy 417.665916 -35.456368) (xy 417.284916 -35.456368) (xy 417.284916 -34.948368)
				)
			)
		)
	)
)
